(kicad_pcb
	(version 20260206)
	(generator "pcbnew")
	(generator_version "10.0")
	(general
		(thickness 1.6)
		(legacy_teardrops no)
	)
	(paper "A4")
	(title_block
		(title "baseboard — 13948-1b.1110WZS1818.brd")
		(comment 1 "Honey Badger (Wiwynn) / footprints 155-161 of 2523")
	)
	(layers
		(0 "F.Cu" signal "TOP")
		(4 "In1.Cu" signal "L2GND")
		(6 "In2.Cu" signal "L3")
		(8 "In3.Cu" signal "L4VCC")
		(10 "In4.Cu" signal "L5VCC")
		(12 "In5.Cu" signal "L6")
		(14 "In6.Cu" signal "L7GND")
		(2 "B.Cu" signal "BOTTOM")
		(9 "F.Adhes" user "F.Adhesive")
		(11 "B.Adhes" user "B.Adhesive")
		(13 "F.Paste" user "Package Geometry/Pastemask Top")
		(15 "B.Paste" user "Package Geometry/Pastemask Bottom")
		(5 "F.SilkS" user "Ref Des/Silkscreen Top")
		(7 "B.SilkS" user "Ref Des/Silkscreen Bottom")
		(1 "F.Mask" user "Board Geometry/Soldermask Top")
		(3 "B.Mask" user "Board Geometry/Soldermask Bottom")
		(17 "Dwgs.User" user "User.Drawings")
		(19 "Cmts.User" user "User.Comments")
		(21 "Eco1.User" user "User.Eco1")
		(23 "Eco2.User" user "User.Eco2")
		(25 "Edge.Cuts" user "Board Geometry/Outline")
		(27 "Margin" user)
		(31 "F.CrtYd" user "Package Geometry/Place Bound Top")
		(29 "B.CrtYd" user "Package Geometry/Place Bound Bottom")
		(35 "F.Fab" user "Ref Des/Assembly Top")
		(33 "B.Fab" user "Ref Des/Assembly Bottom")
	)
	(footprint ""
		(layer "F.Cu")
		(at 181.791864 -22.551136)
		(property "Reference" "R396"
			(at 0 0 0)
			(layer "F.SilkS")
			(hide yes)
			(effects
				(font
					(size 1.27 1.27)
				)
			)
		)
		(property "Value" "150R2F-1-GP"
			(at 0.064008 -3.993896 0)
			(unlocked yes)
			(layer "F.Fab")
			(hide yes)
			(effects
				(font
					(size 1.016 1.016)
					(thickness 0.1524)
				)
			)
		)
		(property "Device Type" "R402H16"
			(at 0.064008 -5.517896 0)
			(unlocked yes)
			(layer "F.Fab")
			(hide yes)
			(effects
				(font
					(size 1.016 1.016)
					(thickness 0.1524)
				)
			)
		)
		(duplicate_pad_numbers_are_jumpers no)
		(fp_line
			(start -0.508 -0.9398)
			(end -0.508 0.9398)
			(stroke
				(width 0.1524)
				(type default)
			)
			(layer "F.SilkS")
		)
		(fp_line
			(start 0.508 -0.9398)
			(end -0.508 -0.9398)
			(stroke
				(width 0.1524)
				(type default)
			)
			(layer "F.SilkS")
		)
		(fp_rect
			(start -0.508 0.9398)
			(end 0.508 -0.9398)
			(stroke
				(width 0)
				(type default)
			)
			(fill no)
			(layer "F.CrtYd")
		)
		(fp_rect
			(start -0.508 0.9398)
			(end 0.508 -0.9398)
			(stroke
				(width 0)
				(type default)
			)
			(fill no)
			(layer "F.Fab")
		)
		(pad "1" smd custom
			(at 0 -0.4445)
			(size 0.1397 0.1397)
			(layers "F.Cu" "F.Mask" "F.Paste")
			(net "PHY_ANEN")
			(options
				(clearance outline)
				(anchor circle)
			)
			(primitives
				(gr_poly
					(pts
						(arc
							(start -0.1778 -0.2794)
							(mid -0.249642 -0.249642)
							(end -0.2794 -0.1778)
						)
						(arc
							(start -0.2794 0.1778)
							(mid -0.249642 0.249642)
							(end -0.1778 0.2794)
						)
						(arc
							(start 0.1778 0.2794)
							(mid 0.249642 0.249642)
							(end 0.2794 0.1778)
						)
						(arc
							(start 0.2794 -0.1778)
							(mid 0.249642 -0.249642)
							(end 0.1778 -0.2794)
						)
					)
					(width 0)
					(fill yes)
				)
			)
		)
		(pad "2" smd custom
			(at 0 0.4445)
			(size 0.1397 0.1397)
			(layers "F.Cu" "F.Mask" "F.Paste")
			(net "GND")
			(options
				(clearance outline)
				(anchor circle)
			)
			(primitives
				(gr_poly
					(pts
						(arc
							(start -0.1778 -0.2794)
							(mid -0.249642 -0.249642)
							(end -0.2794 -0.1778)
						)
						(arc
							(start -0.2794 0.1778)
							(mid -0.249642 0.249642)
							(end -0.1778 0.2794)
						)
						(arc
							(start 0.1778 0.2794)
							(mid 0.249642 0.249642)
							(end 0.2794 0.1778)
						)
						(arc
							(start 0.2794 -0.1778)
							(mid 0.249642 -0.249642)
							(end 0.1778 -0.2794)
						)
					)
					(width 0)
					(fill yes)
				)
			)
		)
	)
	(footprint ""
		(layer "F.Cu")
		(at 183.569864 -38.172136 180)
		(property "Reference" "R390"
			(at 0 0 180)
			(layer "F.SilkS")
			(hide yes)
			(effects
				(font
					(size 1.27 1.27)
				)
			)
		)
		(property "Value" "4K75R2F-1-GP"
			(at 0.064008 -3.993896 180)
			(unlocked yes)
			(layer "F.Fab")
			(hide yes)
			(effects
				(font
					(size 1.016 1.016)
					(thickness 0.1524)
				)
			)
		)
		(property "Device Type" "R402H16"
			(at 0.064008 -5.517896 180)
			(unlocked yes)
			(layer "F.Fab")
			(hide yes)
			(effects
				(font
					(size 1.016 1.016)
					(thickness 0.1524)
				)
			)
		)
		(duplicate_pad_numbers_are_jumpers no)
		(fp_line
			(start 0.508 -0.9398)
			(end -0.508 -0.9398)
			(stroke
				(width 0.1524)
				(type default)
			)
			(layer "F.SilkS")
		)
		(fp_line
			(start -0.508 -0.9398)
			(end -0.508 0.9398)
			(stroke
				(width 0.1524)
				(type default)
			)
			(layer "F.SilkS")
		)
		(fp_rect
			(start -0.508 0.9398)
			(end 0.508 -0.9398)
			(stroke
				(width 0)
				(type default)
			)
			(fill no)
			(layer "F.CrtYd")
		)
		(fp_rect
			(start -0.508 0.9398)
			(end 0.508 -0.9398)
			(stroke
				(width 0)
				(type default)
			)
			(fill no)
			(layer "F.Fab")
		)
		(pad "1" smd custom
			(at 0 -0.4445 180)
			(size 0.1397 0.1397)
			(layers "F.Cu" "F.Mask" "F.Paste")
			(net "PHY_AD0")
			(options
				(clearance outline)
				(anchor circle)
			)
			(primitives
				(gr_poly
					(pts
						(arc
							(start -0.1778 -0.2794)
							(mid -0.249642 -0.249642)
							(end -0.2794 -0.1778)
						)
						(arc
							(start -0.2794 0.1778)
							(mid -0.249642 0.249642)
							(end -0.1778 0.2794)
						)
						(arc
							(start 0.1778 0.2794)
							(mid 0.249642 0.249642)
							(end 0.2794 0.1778)
						)
						(arc
							(start 0.2794 -0.1778)
							(mid 0.249642 -0.249642)
							(end 0.1778 -0.2794)
						)
					)
					(width 0)
					(fill yes)
				)
			)
		)
		(pad "2" smd custom
			(at 0 0.4445 180)
			(size 0.1397 0.1397)
			(layers "F.Cu" "F.Mask" "F.Paste")
			(net "GND")
			(options
				(clearance outline)
				(anchor circle)
			)
			(primitives
				(gr_poly
					(pts
						(arc
							(start -0.1778 -0.2794)
							(mid -0.249642 -0.249642)
							(end -0.2794 -0.1778)
						)
						(arc
							(start -0.2794 0.1778)
							(mid -0.249642 0.249642)
							(end -0.1778 0.2794)
						)
						(arc
							(start 0.1778 0.2794)
							(mid 0.249642 0.249642)
							(end 0.2794 0.1778)
						)
						(arc
							(start 0.2794 -0.1778)
							(mid 0.249642 -0.249642)
							(end 0.1778 -0.2794)
						)
					)
					(width 0)
					(fill yes)
				)
			)
		)
	)
	(footprint ""
		(layer "F.Cu")
		(at 166.614856 -112.404652 180)
		(property "Reference" "PR157"
			(at 0 0 180)
			(layer "F.SilkS")
			(hide yes)
			(effects
				(font
					(size 1.27 1.27)
				)
			)
		)
		(property "Value" "51KR2F-L-GP"
			(at 0.064008 -3.993896 180)
			(unlocked yes)
			(layer "F.Fab")
			(hide yes)
			(effects
				(font
					(size 1.016 1.016)
					(thickness 0.1524)
				)
			)
		)
		(property "Device Type" "R402H16"
			(at 0.064008 -5.517896 180)
			(unlocked yes)
			(layer "F.Fab")
			(hide yes)
			(effects
				(font
					(size 1.016 1.016)
					(thickness 0.1524)
				)
			)
		)
		(duplicate_pad_numbers_are_jumpers no)
		(fp_line
			(start 0.508 -0.9398)
			(end -0.508 -0.9398)
			(stroke
				(width 0.1524)
				(type default)
			)
			(layer "F.SilkS")
		)
		(fp_line
			(start -0.508 -0.9398)
			(end -0.508 0.9398)
			(stroke
				(width 0.1524)
				(type default)
			)
			(layer "F.SilkS")
		)
		(fp_rect
			(start -0.508 0.9398)
			(end 0.508 -0.9398)
			(stroke
				(width 0)
				(type default)
			)
			(fill no)
			(layer "F.CrtYd")
		)
		(fp_rect
			(start -0.508 0.9398)
			(end 0.508 -0.9398)
			(stroke
				(width 0)
				(type default)
			)
			(fill no)
			(layer "F.Fab")
		)
		(pad "1" smd custom
			(at 0 -0.4445 180)
			(size 0.1397 0.1397)
			(layers "F.Cu" "F.Mask" "F.Paste")
			(net "P0V9_E_EN")
			(options
				(clearance outline)
				(anchor circle)
			)
			(primitives
				(gr_poly
					(pts
						(arc
							(start -0.1778 -0.2794)
							(mid -0.249642 -0.249642)
							(end -0.2794 -0.1778)
						)
						(arc
							(start -0.2794 0.1778)
							(mid -0.249642 0.249642)
							(end -0.1778 0.2794)
						)
						(arc
							(start 0.1778 0.2794)
							(mid 0.249642 0.249642)
							(end 0.2794 0.1778)
						)
						(arc
							(start 0.2794 -0.1778)
							(mid 0.249642 -0.249642)
							(end 0.1778 -0.2794)
						)
					)
					(width 0)
					(fill yes)
				)
			)
		)
		(pad "2" smd custom
			(at 0 0.4445 180)
			(size 0.1397 0.1397)
			(layers "F.Cu" "F.Mask" "F.Paste")
			(net "GND")
			(options
				(clearance outline)
				(anchor circle)
			)
			(primitives
				(gr_poly
					(pts
						(arc
							(start -0.1778 -0.2794)
							(mid -0.249642 -0.249642)
							(end -0.2794 -0.1778)
						)
						(arc
							(start -0.2794 0.1778)
							(mid -0.249642 0.249642)
							(end -0.1778 0.2794)
						)
						(arc
							(start 0.1778 0.2794)
							(mid 0.249642 0.249642)
							(end 0.2794 0.1778)
						)
						(arc
							(start 0.2794 -0.1778)
							(mid 0.249642 -0.249642)
							(end 0.1778 -0.2794)
						)
					)
					(width 0)
					(fill yes)
				)
			)
		)
	)
	(footprint ""
		(layer "F.Cu")
		(at 198.119492 -171.463716 180)
		(property "Reference" "R480"
			(at 0 0 180)
			(layer "F.SilkS")
			(hide yes)
			(effects
				(font
					(size 1.27 1.27)
				)
			)
		)
		(property "Value" "10KR2F-2-GP"
			(at 0.064008 -3.993896 180)
			(unlocked yes)
			(layer "F.Fab")
			(hide yes)
			(effects
				(font
					(size 1.016 1.016)
					(thickness 0.1524)
				)
			)
		)
		(property "Device Type" "R402H16"
			(at 0.064008 -5.517896 180)
			(unlocked yes)
			(layer "F.Fab")
			(hide yes)
			(effects
				(font
					(size 1.016 1.016)
					(thickness 0.1524)
				)
			)
		)
		(duplicate_pad_numbers_are_jumpers no)
		(fp_line
			(start 0.508 -0.9398)
			(end -0.508 -0.9398)
			(stroke
				(width 0.1524)
				(type default)
			)
			(layer "F.SilkS")
		)
		(fp_line
			(start -0.508 -0.9398)
			(end -0.508 0.9398)
			(stroke
				(width 0.1524)
				(type default)
			)
			(layer "F.SilkS")
		)
		(fp_rect
			(start -0.508 0.9398)
			(end 0.508 -0.9398)
			(stroke
				(width 0)
				(type default)
			)
			(fill no)
			(layer "F.CrtYd")
		)
		(fp_rect
			(start -0.508 0.9398)
			(end 0.508 -0.9398)
			(stroke
				(width 0)
				(type default)
			)
			(fill no)
			(layer "F.Fab")
		)
		(pad "1" smd custom
			(at 0 -0.4445 180)
			(size 0.1397 0.1397)
			(layers "F.Cu" "F.Mask" "F.Paste")
			(net "P3V3_STBY")
			(options
				(clearance outline)
				(anchor circle)
			)
			(primitives
				(gr_poly
					(pts
						(arc
							(start -0.1778 -0.2794)
							(mid -0.249642 -0.249642)
							(end -0.2794 -0.1778)
						)
						(arc
							(start -0.2794 0.1778)
							(mid -0.249642 0.249642)
							(end -0.1778 0.2794)
						)
						(arc
							(start 0.1778 0.2794)
							(mid 0.249642 0.249642)
							(end 0.2794 0.1778)
						)
						(arc
							(start 0.2794 -0.1778)
							(mid 0.249642 -0.249642)
							(end 0.1778 -0.2794)
						)
					)
					(width 0)
					(fill yes)
				)
			)
		)
		(pad "2" smd custom
			(at 0 0.4445 180)
			(size 0.1397 0.1397)
			(layers "F.Cu" "F.Mask" "F.Paste")
			(net "INVERTER_G2")
			(options
				(clearance outline)
				(anchor circle)
			)
			(primitives
				(gr_poly
					(pts
						(arc
							(start -0.1778 -0.2794)
							(mid -0.249642 -0.249642)
							(end -0.2794 -0.1778)
						)
						(arc
							(start -0.2794 0.1778)
							(mid -0.249642 0.249642)
							(end -0.1778 0.2794)
						)
						(arc
							(start 0.1778 0.2794)
							(mid 0.249642 0.249642)
							(end 0.2794 0.1778)
						)
						(arc
							(start 0.2794 -0.1778)
							(mid 0.249642 -0.249642)
							(end 0.1778 -0.2794)
						)
					)
					(width 0)
					(fill yes)
				)
			)
		)
	)
	(footprint ""
		(layer "F.Cu")
		(at 84.21497 -112.014 180)
		(property "Reference" "SC1228"
			(at 0 0 180)
			(layer "F.SilkS")
			(hide yes)
			(effects
				(font
					(size 1.27 1.27)
				)
			)
		)
		(property "Value" "SCD1U6D3V1KX-GP"
			(at -2.8321 -1.7399 180)
			(unlocked yes)
			(layer "F.Fab")
			(hide yes)
			(effects
				(font
					(size 1.016 1.016)
					(thickness 0.1524)
				)
			)
		)
		(property "Device Type" "C0201H13"
			(at -2.8321 -3.2639 180)
			(unlocked yes)
			(layer "F.Fab")
			(hide yes)
			(effects
				(font
					(size 1.016 1.016)
					(thickness 0.1524)
				)
			)
		)
		(duplicate_pad_numbers_are_jumpers no)
		(fp_rect
			(start -0.2794 0.6477)
			(end 0.2794 -0.6477)
			(stroke
				(width 0)
				(type default)
			)
			(fill no)
			(layer "F.CrtYd")
		)
		(fp_rect
			(start -0.2794 0.6477)
			(end 0.2794 -0.6477)
			(stroke
				(width 0)
				(type default)
			)
			(fill no)
			(layer "F.Fab")
		)
		(pad "1" smd custom
			(at 0 -0.2794 180)
			(size 0.0762 0.0762)
			(layers "F.Cu" "F.Mask" "F.Paste")
			(net "P1V8_E")
			(options
				(clearance outline)
				(anchor circle)
			)
			(primitives
				(gr_poly
					(pts
						(arc
							(start 0.1524 -0.127)
							(mid 0.137521 -0.162921)
							(end 0.1016 -0.1778)
						)
						(arc
							(start -0.1016 -0.1778)
							(mid -0.137521 -0.162921)
							(end -0.1524 -0.127)
						)
						(arc
							(start -0.1524 0.127)
							(mid -0.137521 0.162921)
							(end -0.1016 0.1778)
						)
						(arc
							(start 0.1016 0.1778)
							(mid 0.137521 0.162921)
							(end 0.1524 0.127)
						)
					)
					(width 0)
					(fill yes)
				)
			)
		)
		(pad "2" smd custom
			(at 0 0.2794 180)
			(size 0.0762 0.0762)
			(layers "F.Cu" "F.Mask" "F.Paste")
			(net "GND")
			(options
				(clearance outline)
				(anchor circle)
			)
			(primitives
				(gr_poly
					(pts
						(arc
							(start 0.1524 -0.127)
							(mid 0.137521 -0.162921)
							(end 0.1016 -0.1778)
						)
						(arc
							(start -0.1016 -0.1778)
							(mid -0.137521 -0.162921)
							(end -0.1524 -0.127)
						)
						(arc
							(start -0.1524 0.127)
							(mid -0.137521 0.162921)
							(end -0.1016 0.1778)
						)
						(arc
							(start 0.1016 0.1778)
							(mid 0.137521 0.162921)
							(end 0.1524 0.127)
						)
					)
					(width 0)
					(fill yes)
				)
			)
		)
	)
	(footprint ""
		(layer "F.Cu")
		(at 97.54997 -80.518)
		(property "Reference" "STP102"
			(at 0 0 0)
			(layer "F.SilkS")
			(hide yes)
			(effects
				(font
					(size 1.27 1.27)
				)
			)
		)
		(property "Value" "TPAD28"
			(at 0.0127 -1.8034 0)
			(unlocked yes)
			(layer "F.Fab")
			(hide yes)
			(effects
				(font
					(size 1.016 1.016)
					(thickness 0.1524)
				)
			)
		)
		(property "Device Type" "TPAD28"
			(at 0.0127 -3.3274 0)
			(unlocked yes)
			(layer "F.Fab")
			(hide yes)
			(effects
				(font
					(size 1.016 1.016)
					(thickness 0.1524)
				)
			)
		)
		(duplicate_pad_numbers_are_jumpers no)
		(fp_poly
			(pts
				(arc
					(start 0.3556 0)
					(mid -0.3556 0)
					(end 0.3556 0)
				)
			)
			(stroke
				(width 0)
				(type default)
			)
			(fill no)
			(layer "F.CrtYd")
		)
		(fp_poly
			(pts
				(arc
					(start 0.6096 0)
					(mid -0.6096 0)
					(end 0.6096 0)
				)
			)
			(stroke
				(width 0)
				(type default)
			)
			(fill no)
			(layer "F.Fab")
		)
		(pad "1" smd circle
			(at 0 0)
			(size 0.7112 0.7112)
			(layers "F.Cu" "F.Mask" "F.Paste")
			(net "TMUX_EN")
		)
	)
	(footprint ""
		(layer "F.Cu")
		(at 79.38897 -112.014)
		(property "Reference" "PR171"
			(at 0 0 0)
			(layer "F.SilkS")
			(hide yes)
			(effects
				(font
					(size 1.27 1.27)
				)
			)
		)
		(property "Value" "1KR2J-1-GP"
			(at 0.064008 -3.993896 0)
			(unlocked yes)
			(layer "F.Fab")
			(hide yes)
			(effects
				(font
					(size 1.016 1.016)
					(thickness 0.1524)
				)
			)
		)
		(property "Device Type" "R402H16"
			(at 0.064008 -5.517896 0)
			(unlocked yes)
			(layer "F.Fab")
			(hide yes)
			(effects
				(font
					(size 1.016 1.016)
					(thickness 0.1524)
				)
			)
		)
		(duplicate_pad_numbers_are_jumpers no)
		(fp_line
			(start -0.508 -0.9398)
			(end -0.508 0.9398)
			(stroke
				(width 0.1524)
				(type default)
			)
			(layer "F.SilkS")
		)
		(fp_line
			(start 0.508 -0.9398)
			(end -0.508 -0.9398)
			(stroke
				(width 0.1524)
				(type default)
			)
			(layer "F.SilkS")
		)
		(fp_rect
			(start -0.508 0.9398)
			(end 0.508 -0.9398)
			(stroke
				(width 0)
				(type default)
			)
			(fill no)
			(layer "F.CrtYd")
		)
		(fp_rect
			(start -0.508 0.9398)
			(end 0.508 -0.9398)
			(stroke
				(width 0)
				(type default)
			)
			(fill no)
			(layer "F.Fab")
		)
		(pad "1" smd custom
			(at 0 -0.4445)
			(size 0.1397 0.1397)
			(layers "F.Cu" "F.Mask" "F.Paste")
			(net "GND")
			(options
				(clearance outline)
				(anchor circle)
			)
			(primitives
				(gr_poly
					(pts
						(arc
							(start -0.1778 -0.2794)
							(mid -0.249642 -0.249642)
							(end -0.2794 -0.1778)
						)
						(arc
							(start -0.2794 0.1778)
							(mid -0.249642 0.249642)
							(end -0.1778 0.2794)
						)
						(arc
							(start 0.1778 0.2794)
							(mid 0.249642 0.249642)
							(end 0.2794 0.1778)
						)
						(arc
							(start 0.2794 -0.1778)
							(mid 0.249642 -0.249642)
							(end 0.1778 -0.2794)
						)
					)
					(width 0)
					(fill yes)
				)
			)
		)
		(pad "2" smd custom
			(at 0 0.4445)
			(size 0.1397 0.1397)
			(layers "F.Cu" "F.Mask" "F.Paste")
			(net "P1V8_E")
			(options
				(clearance outline)
				(anchor circle)
			)
			(primitives
				(gr_poly
					(pts
						(arc
							(start -0.1778 -0.2794)
							(mid -0.249642 -0.249642)
							(end -0.2794 -0.1778)
						)
						(arc
							(start -0.2794 0.1778)
							(mid -0.249642 0.249642)
							(end -0.1778 0.2794)
						)
						(arc
							(start 0.1778 0.2794)
							(mid 0.249642 0.249642)
							(end 0.2794 0.1778)
						)
						(arc
							(start 0.2794 -0.1778)
							(mid 0.249642 -0.249642)
							(end 0.1778 -0.2794)
						)
					)
					(width 0)
					(fill yes)
				)
			)
		)
	)
)
